(kicad_pcb
	(version 20260206)
	(generator "pcbnew")
	(generator_version "10.0")
	(general
		(thickness 1.6)
		(legacy_teardrops no)
	)
	(paper "A4")
	(title_block
		(title "fcb — Lightning_FCB_BRD.brd")
		(comment 1 "Lightning (Wiwynn / Facebook NVMe JBOF) / footprints 126-131 of 495")
	)
	(layers
		(0 "F.Cu" signal "TOP")
		(4 "In1.Cu" signal "L2GND")
		(6 "In2.Cu" signal "L3VCC")
		(2 "B.Cu" signal "BOTTOM")
		(9 "F.Adhes" user "F.Adhesive")
		(11 "B.Adhes" user "B.Adhesive")
		(13 "F.Paste" user "Package Geometry/Pastemask Top")
		(15 "B.Paste" user "Package Geometry/Pastemask Bottom")
		(5 "F.SilkS" user "Ref Des/Silkscreen Top")
		(7 "B.SilkS" user "Ref Des/Silkscreen Bottom")
		(1 "F.Mask" user "Board Geometry/Soldermask Top")
		(3 "B.Mask" user "Board Geometry/Soldermask Bottom")
		(17 "Dwgs.User" user "User.Drawings")
		(19 "Cmts.User" user "User.Comments")
		(21 "Eco1.User" user "User.Eco1")
		(23 "Eco2.User" user "User.Eco2")
		(25 "Edge.Cuts" user "Board Geometry/Outline")
		(27 "Margin" user)
		(31 "F.CrtYd" user "Package Geometry/Place Bound Top")
		(29 "B.CrtYd" user "Package Geometry/Place Bound Bottom")
		(35 "F.Fab" user "Ref Des/Assembly Top")
		(33 "B.Fab" user "Ref Des/Assembly Bottom")
	)
	(footprint ""
		(layer "F.Cu")
		(at 38.67531 -153.713434)
		(property "Reference" "C1"
			(at 0 0 0)
			(layer "F.SilkS")
			(hide yes)
			(effects
				(font
					(size 1.27 1.27)
				)
			)
		)
		(property "Value" "SC10U25V5KX-GP"
			(at -0.0762 -6.1214 0)
			(unlocked yes)
			(layer "F.Fab")
			(hide yes)
			(effects
				(font
					(size 1.016 1.016)
					(thickness 0.1524)
				)
			)
		)
		(property "Device Type" "C805H56"
			(at -0.0762 -8.1534 0)
			(unlocked yes)
			(layer "F.Fab")
			(hide yes)
			(effects
				(font
					(size 1.016 1.016)
					(thickness 0.1524)
				)
			)
		)
		(duplicate_pad_numbers_are_jumpers no)
		(fp_line
			(start 0.635 0)
			(end -0.635 0)
			(stroke
				(width 0.508)
				(type default)
			)
			(layer "F.SilkS")
		)
		(fp_rect
			(start -0.9652 1.778)
			(end 0.9652 -1.778)
			(stroke
				(width 0)
				(type default)
			)
			(fill no)
			(layer "F.CrtYd")
		)
		(fp_poly
			(pts
				(xy -0.9652 -1.778) (xy 0.9652 -1.778) (xy 0.9652 1.778) (xy -0.9652 1.778)
			)
			(stroke
				(width 0)
				(type default)
			)
			(fill no)
			(layer "F.Fab")
		)
		(pad "1" smd rect
			(at 0 -0.9652)
			(size 1.397 1.143)
			(layers "F.Cu" "F.Mask" "F.Paste")
			(net "NCT7904_3VDD")
		)
		(pad "2" smd rect
			(at 0 0.9652)
			(size 1.397 1.143)
			(layers "F.Cu" "F.Mask" "F.Paste")
			(net "GND")
		)
	)
	(footprint ""
		(layer "F.Cu")
		(at 35.59429 -150.680166 180)
		(property "Reference" "TP11"
			(at 0 0 180)
			(layer "F.SilkS")
			(hide yes)
			(effects
				(font
					(size 1.27 1.27)
				)
			)
		)
		(property "Value" "TPAD32-GP"
			(at 0 -3.166364 180)
			(unlocked yes)
			(layer "F.Fab")
			(hide yes)
			(effects
				(font
					(size 1.016 1.016)
					(thickness 0.1524)
				)
			)
		)
		(property "Device Type" "TPAD32"
			(at 0 -4.690618 180)
			(unlocked yes)
			(layer "F.Fab")
			(hide yes)
			(effects
				(font
					(size 1.016 1.016)
					(thickness 0.1524)
				)
			)
		)
		(duplicate_pad_numbers_are_jumpers no)
		(fp_poly
			(pts
				(arc
					(start 0.7112 0)
					(mid -0.7112 0)
					(end 0.7112 0)
				)
			)
			(stroke
				(width 0)
				(type default)
			)
			(fill no)
			(layer "F.CrtYd")
		)
		(fp_poly
			(pts
				(arc
					(start 0.7112 0)
					(mid -0.7112 0)
					(end 0.7112 0)
				)
			)
			(stroke
				(width 0)
				(type default)
			)
			(fill no)
			(layer "F.Fab")
		)
		(pad "1" smd circle
			(at 0 0 180)
			(size 0.8128 0.8128)
			(layers "F.Cu" "F.Mask" "F.Paste")
			(net "NCT7904_VSEN12")
		)
	)
	(footprint ""
		(layer "F.Cu")
		(at 30.6832 -149.073616)
		(property "Reference" "R35"
			(at 0 0 0)
			(layer "F.SilkS")
			(hide yes)
			(effects
				(font
					(size 1.27 1.27)
				)
			)
		)
		(property "Value" "10KR2F-2-GP"
			(at 0.064008 -3.993896 0)
			(unlocked yes)
			(layer "F.Fab")
			(hide yes)
			(effects
				(font
					(size 1.016 1.016)
					(thickness 0.1524)
				)
			)
		)
		(property "Device Type" "R402H16"
			(at 0.064008 -5.517896 0)
			(unlocked yes)
			(layer "F.Fab")
			(hide yes)
			(effects
				(font
					(size 1.016 1.016)
					(thickness 0.1524)
				)
			)
		)
		(duplicate_pad_numbers_are_jumpers no)
		(fp_line
			(start -0.508 -0.9398)
			(end -0.508 0.9398)
			(stroke
				(width 0.1524)
				(type default)
			)
			(layer "F.SilkS")
		)
		(fp_line
			(start 0.508 -0.9398)
			(end -0.508 -0.9398)
			(stroke
				(width 0.1524)
				(type default)
			)
			(layer "F.SilkS")
		)
		(fp_rect
			(start -0.508 0.9398)
			(end 0.508 -0.9398)
			(stroke
				(width 0)
				(type default)
			)
			(fill no)
			(layer "F.CrtYd")
		)
		(fp_rect
			(start -0.508 0.9398)
			(end 0.508 -0.9398)
			(stroke
				(width 0)
				(type default)
			)
			(fill no)
			(layer "F.Fab")
		)
		(pad "1" smd custom
			(at 0 -0.4445)
			(size 0.1397 0.1397)
			(layers "F.Cu" "F.Mask" "F.Paste")
			(net "NCT7904_VSEN6")
			(options
				(clearance outline)
				(anchor circle)
			)
			(primitives
				(gr_poly
					(pts
						(arc
							(start -0.1778 -0.2794)
							(mid -0.249642 -0.249642)
							(end -0.2794 -0.1778)
						)
						(arc
							(start -0.2794 0.1778)
							(mid -0.249642 0.249642)
							(end -0.1778 0.2794)
						)
						(arc
							(start 0.1778 0.2794)
							(mid 0.249642 0.249642)
							(end 0.2794 0.1778)
						)
						(arc
							(start 0.2794 -0.1778)
							(mid 0.249642 -0.249642)
							(end 0.1778 -0.2794)
						)
					)
					(width 0)
					(fill yes)
				)
			)
		)
		(pad "2" smd custom
			(at 0 0.4445)
			(size 0.1397 0.1397)
			(layers "F.Cu" "F.Mask" "F.Paste")
			(net "GND")
			(options
				(clearance outline)
				(anchor circle)
			)
			(primitives
				(gr_poly
					(pts
						(arc
							(start -0.1778 -0.2794)
							(mid -0.249642 -0.249642)
							(end -0.2794 -0.1778)
						)
						(arc
							(start -0.2794 0.1778)
							(mid -0.249642 0.249642)
							(end -0.1778 0.2794)
						)
						(arc
							(start 0.1778 0.2794)
							(mid 0.249642 0.249642)
							(end 0.2794 0.1778)
						)
						(arc
							(start 0.2794 -0.1778)
							(mid 0.249642 -0.249642)
							(end 0.1778 -0.2794)
						)
					)
					(width 0)
					(fill yes)
				)
			)
		)
	)
	(footprint ""
		(layer "F.Cu")
		(at 4.040124 -372.65991 -90)
		(property "Reference" "CN2"
			(at 0 0 270)
			(layer "F.SilkS")
			(hide yes)
			(effects
				(font
					(size 1.27 1.27)
				)
			)
		)
		(property "Value" "JWT-CON5-42-GP"
			(at -7.8105 2.9591 270)
			(unlocked yes)
			(layer "F.Fab")
			(hide yes)
			(effects
				(font
					(size 1.016 1.016)
					(thickness 0.1524)
				)
			)
		)
		(property "Device Type" "A2541WR0-1TX5PA-6T-0E"
			(at -7.8105 1.4351 270)
			(unlocked yes)
			(layer "F.Fab")
			(hide yes)
			(effects
				(font
					(size 1.016 1.016)
					(thickness 0.1524)
				)
			)
		)
		(duplicate_pad_numbers_are_jumpers no)
		(fp_line
			(start -6.604 10.287)
			(end 6.604 10.287)
			(stroke
				(width 0.1524)
				(type default)
			)
			(layer "F.SilkS")
		)
		(fp_line
			(start 6.604 10.287)
			(end 6.604 -0.9652)
			(stroke
				(width 0.1524)
				(type default)
			)
			(layer "F.SilkS")
		)
		(fp_line
			(start -6.604 -0.9652)
			(end -6.604 10.287)
			(stroke
				(width 0.1524)
				(type default)
			)
			(layer "F.SilkS")
		)
		(fp_line
			(start 6.604 -0.9652)
			(end -6.604 -0.9652)
			(stroke
				(width 0.1524)
				(type default)
			)
			(layer "F.SilkS")
		)
		(fp_line
			(start -6.731 -1.0922)
			(end -6.731 0.1778)
			(stroke
				(width 0.4064)
				(type default)
			)
			(layer "F.SilkS")
		)
		(fp_line
			(start -5.461 -1.0922)
			(end -6.731 -1.0922)
			(stroke
				(width 0.4064)
				(type default)
			)
			(layer "F.SilkS")
		)
		(fp_circle
			(center -5.08 0)
			(end -5.08 -1.0668)
			(stroke
				(width 0.3048)
				(type default)
			)
			(fill no)
			(layer "F.SilkS")
		)
		(fp_circle
			(center -2.54 0)
			(end -2.54 -1.0668)
			(stroke
				(width 0.3048)
				(type default)
			)
			(fill no)
			(layer "F.SilkS")
		)
		(fp_circle
			(center 0 0)
			(end 0 -1.0668)
			(stroke
				(width 0.3048)
				(type default)
			)
			(fill no)
			(layer "F.SilkS")
		)
		(fp_circle
			(center 2.54 0)
			(end 2.54 -1.0668)
			(stroke
				(width 0.3048)
				(type default)
			)
			(fill no)
			(layer "F.SilkS")
		)
		(fp_circle
			(center 5.08 0)
			(end 5.08 -1.0668)
			(stroke
				(width 0.3048)
				(type default)
			)
			(fill no)
			(layer "F.SilkS")
		)
		(fp_rect
			(start -6.35 10.033)
			(end 6.35 -0.3302)
			(stroke
				(width 0)
				(type default)
			)
			(fill no)
			(layer "F.CrtYd")
		)
		(fp_poly
			(pts
				(xy -6.35 -0.3302) (xy 6.858 -0.3302) (xy 6.858 -1.2192) (xy -6.858 -1.2192) (xy -6.858 10.541)
				(xy 6.858 10.541) (xy 6.858 -0.3175) (xy 6.35 -0.3175) (xy 6.35 10.033) (xy -6.35 10.033)
			)
			(stroke
				(width 0)
				(type default)
			)
			(fill no)
			(layer "F.CrtYd")
		)
		(fp_rect
			(start -6.858 10.541)
			(end 6.858 -1.2192)
			(stroke
				(width 0)
				(type default)
			)
			(fill no)
			(layer "F.Fab")
		)
		(pad "1" thru_hole circle
			(at -5.08 0 270)
			(size 1.4224 1.4224)
			(drill 1.016)
			(layers "*.Cu" "*.Mask")
			(remove_unused_layers no)
			(net "GND")
			(clearance 0.1524)
			(thermal_gap 0.1524)
		)
		(pad "2" thru_hole circle
			(at -2.54 0 270)
			(size 1.4224 1.4224)
			(drill 1.016)
			(layers "*.Cu" "*.Mask")
			(remove_unused_layers no)
			(net "P12V_FAN2")
			(clearance 0.1524)
			(thermal_gap 0.1524)
		)
		(pad "3" thru_hole circle
			(at 0 0 270)
			(size 1.4224 1.4224)
			(drill 1.016)
			(layers "*.Cu" "*.Mask")
			(remove_unused_layers no)
			(net "FAN_TACH4")
			(clearance 0.1524)
			(thermal_gap 0.1524)
		)
		(pad "4" thru_hole circle
			(at 2.54 0 270)
			(size 1.4224 1.4224)
			(drill 1.016)
			(layers "*.Cu" "*.Mask")
			(remove_unused_layers no)
			(net "PWM_OUT_FAN2_NET")
			(clearance 0.1524)
			(thermal_gap 0.1524)
		)
		(pad "5" thru_hole circle
			(at 5.08 0 270)
			(size 1.4224 1.4224)
			(drill 1.016)
			(layers "*.Cu" "*.Mask")
			(remove_unused_layers no)
			(net "FAN_TACH3")
			(clearance 0.1524)
			(thermal_gap 0.1524)
		)
	)
	(footprint ""
		(layer "F.Cu")
		(at 43.019726 -366.069626)
		(property "Reference" "PQ6"
			(at 0 0 0)
			(layer "F.SilkS")
			(hide yes)
			(effects
				(font
					(size 1.27 1.27)
				)
			)
		)
		(property "Value" "PMBS3904-1-GP"
			(at 0 -9.0932 0)
			(unlocked yes)
			(layer "F.Fab")
			(hide yes)
			(effects
				(font
					(size 1.016 1.016)
					(thickness 0.1524)
				)
			)
		)
		(property "Device Type" "SOT-23-10H44"
			(at 0 -10.6172 0)
			(unlocked yes)
			(layer "F.Fab")
			(hide yes)
			(effects
				(font
					(size 1.016 1.016)
					(thickness 0.1524)
				)
			)
		)
		(duplicate_pad_numbers_are_jumpers no)
		(fp_line
			(start -1.7526 1.8796)
			(end -1.7526 0.9906)
			(stroke
				(width 0.3302)
				(type default)
			)
			(layer "F.SilkS")
		)
		(fp_line
			(start -1.651 -1.778)
			(end -1.651 1.778)
			(stroke
				(width 0.1524)
				(type default)
			)
			(layer "F.SilkS")
		)
		(fp_line
			(start -1.651 1.778)
			(end 1.651 1.778)
			(stroke
				(width 0.1524)
				(type default)
			)
			(layer "F.SilkS")
		)
		(fp_line
			(start -1.279398 2.152142)
			(end -0.9906 1.86309)
			(stroke
				(width 0.0127)
				(type default)
			)
			(layer "F.SilkS")
		)
		(fp_line
			(start -1.279144 2.15265)
			(end -0.701294 2.15265)
			(stroke
				(width 0.0127)
				(type default)
			)
			(layer "F.SilkS")
		)
		(fp_line
			(start -1.260856 2.1336)
			(end -0.720344 2.1336)
			(stroke
				(width 0.0127)
				(type default)
			)
			(layer "F.SilkS")
		)
		(fp_line
			(start -1.251458 2.124202)
			(end -0.729996 2.124202)
			(stroke
				(width 0.0127)
				(type default)
			)
			(layer "F.SilkS")
		)
		(fp_line
			(start -1.241806 2.11455)
			(end -0.739394 2.11455)
			(stroke
				(width 0.0127)
				(type default)
			)
			(layer "F.SilkS")
		)
		(fp_line
			(start -1.232408 2.105152)
			(end -0.749046 2.105152)
			(stroke
				(width 0.0127)
				(type default)
			)
			(layer "F.SilkS")
		)
		(fp_line
			(start -1.222756 2.0955)
			(end -0.758444 2.0955)
			(stroke
				(width 0.0127)
				(type default)
			)
			(layer "F.SilkS")
		)
		(fp_line
			(start -1.213358 2.086102)
			(end -0.768096 2.086102)
			(stroke
				(width 0.0127)
				(type default)
			)
			(layer "F.SilkS")
		)
		(fp_line
			(start -1.203706 2.07645)
			(end -0.777494 2.07645)
			(stroke
				(width 0.0127)
				(type default)
			)
			(layer "F.SilkS")
		)
		(fp_line
			(start -1.194308 2.067052)
			(end -0.787146 2.067052)
			(stroke
				(width 0.0127)
				(type default)
			)
			(layer "F.SilkS")
		)
		(fp_line
			(start -1.184656 2.0574)
			(end -0.796544 2.0574)
			(stroke
				(width 0.0127)
				(type default)
			)
			(layer "F.SilkS")
		)
		(fp_line
			(start -1.175258 2.048002)
			(end -0.806196 2.048002)
			(stroke
				(width 0.0127)
				(type default)
			)
			(layer "F.SilkS")
		)
		(fp_line
			(start -1.165606 2.03835)
			(end -0.815594 2.03835)
			(stroke
				(width 0.0127)
				(type default)
			)
			(layer "F.SilkS")
		)
		(fp_line
			(start -1.156208 2.028952)
			(end -0.825246 2.028952)
			(stroke
				(width 0.0127)
				(type default)
			)
			(layer "F.SilkS")
		)
		(fp_line
			(start -1.146556 2.0193)
			(end -0.834644 2.0193)
			(stroke
				(width 0.0127)
				(type default)
			)
			(layer "F.SilkS")
		)
		(fp_line
			(start -1.137158 2.009902)
			(end -0.844296 2.009902)
			(stroke
				(width 0.0127)
				(type default)
			)
			(layer "F.SilkS")
		)
		(fp_line
			(start -1.127506 2.00025)
			(end -0.853694 2.00025)
			(stroke
				(width 0.0127)
				(type default)
			)
			(layer "F.SilkS")
		)
		(fp_line
			(start -1.118108 1.990852)
			(end -0.863346 1.990852)
			(stroke
				(width 0.0127)
				(type default)
			)
			(layer "F.SilkS")
		)
		(fp_line
			(start -1.108456 1.9812)
			(end -0.872744 1.9812)
			(stroke
				(width 0.0127)
				(type default)
			)
			(layer "F.SilkS")
		)
		(fp_line
			(start -1.099058 1.971802)
			(end -0.882396 1.971802)
			(stroke
				(width 0.0127)
				(type default)
			)
			(layer "F.SilkS")
		)
		(fp_line
			(start -1.089406 1.96215)
			(end -0.891794 1.96215)
			(stroke
				(width 0.0127)
				(type default)
			)
			(layer "F.SilkS")
		)
		(fp_line
			(start -1.080008 1.952752)
			(end -0.901446 1.952752)
			(stroke
				(width 0.0127)
				(type default)
			)
			(layer "F.SilkS")
		)
		(fp_line
			(start -1.070356 1.9431)
			(end -0.910844 1.9431)
			(stroke
				(width 0.0127)
				(type default)
			)
			(layer "F.SilkS")
		)
		(fp_line
			(start -1.060958 1.933702)
			(end -0.920496 1.933702)
			(stroke
				(width 0.0127)
				(type default)
			)
			(layer "F.SilkS")
		)
		(fp_line
			(start -1.051306 1.92405)
			(end -0.929894 1.92405)
			(stroke
				(width 0.0127)
				(type default)
			)
			(layer "F.SilkS")
		)
		(fp_line
			(start -1.041908 1.914652)
			(end -0.939546 1.914652)
			(stroke
				(width 0.0127)
				(type default)
			)
			(layer "F.SilkS")
		)
		(fp_line
			(start -1.032256 1.905)
			(end -0.948944 1.905)
			(stroke
				(width 0.0127)
				(type default)
			)
			(layer "F.SilkS")
		)
		(fp_line
			(start -1.022858 1.895602)
			(end -0.958596 1.895602)
			(stroke
				(width 0.0127)
				(type default)
			)
			(layer "F.SilkS")
		)
		(fp_line
			(start -1.013206 1.88595)
			(end -0.967994 1.88595)
			(stroke
				(width 0.0127)
				(type default)
			)
			(layer "F.SilkS")
		)
		(fp_line
			(start -1.003808 1.876552)
			(end -0.977646 1.876552)
			(stroke
				(width 0.0127)
				(type default)
			)
			(layer "F.SilkS")
		)
		(fp_line
			(start -0.994156 1.8669)
			(end -0.987044 1.8669)
			(stroke
				(width 0.0127)
				(type default)
			)
			(layer "F.SilkS")
		)
		(fp_line
			(start -0.9906 1.86309)
			(end -0.701294 2.15265)
			(stroke
				(width 0.0127)
				(type default)
			)
			(layer "F.SilkS")
		)
		(fp_line
			(start -0.719074 2.145538)
			(end -1.265936 2.14122)
			(stroke
				(width 0.0127)
				(type default)
			)
			(layer "F.SilkS")
		)
		(fp_line
			(start -0.71628 2.15265)
			(end -1.26492 2.15265)
			(stroke
				(width 0.0127)
				(type default)
			)
			(layer "F.SilkS")
		)
		(fp_line
			(start -0.635 1.8796)
			(end -1.7526 1.8796)
			(stroke
				(width 0.3302)
				(type default)
			)
			(layer "F.SilkS")
		)
		(fp_line
			(start 1.651 -1.778)
			(end -1.651 -1.778)
			(stroke
				(width 0.1524)
				(type default)
			)
			(layer "F.SilkS")
		)
		(fp_line
			(start 1.651 1.778)
			(end 1.651 -1.778)
			(stroke
				(width 0.1524)
				(type default)
			)
			(layer "F.SilkS")
		)
		(fp_poly
			(pts
				(xy -1.285748 2.159) (xy -1.285748 1.8796) (xy -1.778 1.8796) (xy -1.778 -1.8796) (xy 1.778 -1.8796)
				(xy 1.778 1.8796) (xy -0.694944 1.8796) (xy -0.694944 2.159)
			)
			(stroke
				(width 0)
				(type default)
			)
			(fill no)
			(layer "F.CrtYd")
		)
		(fp_poly
			(pts
				(xy -1.285748 2.159) (xy -1.285748 1.8796) (xy -1.778 1.8796) (xy -1.778 -1.8796) (xy 1.778 -1.8796)
				(xy 1.778 1.8796) (xy -0.694944 1.8796) (xy -0.694944 2.159)
			)
			(stroke
				(width 0)
				(type default)
			)
			(fill no)
			(layer "F.Fab")
		)
		(pad "1" smd rect
			(at -0.98425 0.9525)
			(size 0.762 1.143)
			(layers "F.Cu" "F.Mask" "F.Paste")
			(net "ADM1276_LATCH#")
		)
		(pad "2" smd rect
			(at 0.98425 0.9525)
			(size 0.762 1.143)
			(layers "F.Cu" "F.Mask" "F.Paste")
			(net "GND")
		)
		(pad "3" smd rect
			(at 0 -0.9525)
			(size 0.762 1.143)
			(layers "F.Cu" "F.Mask" "F.Paste")
			(net "TEMP_ALM#_REVERSE")
		)
	)
	(footprint ""
		(layer "F.Cu")
		(at 8.2296 -450.6976 -90)
		(property "Reference" "R95"
			(at 0 0 270)
			(layer "F.SilkS")
			(hide yes)
			(effects
				(font
					(size 1.27 1.27)
				)
			)
		)
		(property "Value" "4K7R2F-GP"
			(at 0.064008 -3.993896 270)
			(unlocked yes)
			(layer "F.Fab")
			(hide yes)
			(effects
				(font
					(size 1.016 1.016)
					(thickness 0.1524)
				)
			)
		)
		(property "Device Type" "R402H16"
			(at 0.064008 -5.517896 270)
			(unlocked yes)
			(layer "F.Fab")
			(hide yes)
			(effects
				(font
					(size 1.016 1.016)
					(thickness 0.1524)
				)
			)
		)
		(duplicate_pad_numbers_are_jumpers no)
		(fp_line
			(start -0.508 -0.9398)
			(end -0.508 0.9398)
			(stroke
				(width 0.1524)
				(type default)
			)
			(layer "F.SilkS")
		)
		(fp_line
			(start 0.508 -0.9398)
			(end -0.508 -0.9398)
			(stroke
				(width 0.1524)
				(type default)
			)
			(layer "F.SilkS")
		)
		(fp_rect
			(start -0.508 0.9398)
			(end 0.508 -0.9398)
			(stroke
				(width 0)
				(type default)
			)
			(fill no)
			(layer "F.CrtYd")
		)
		(fp_rect
			(start -0.508 0.9398)
			(end 0.508 -0.9398)
			(stroke
				(width 0)
				(type default)
			)
			(fill no)
			(layer "F.Fab")
		)
		(pad "1" smd custom
			(at 0 -0.4445 270)
			(size 0.1397 0.1397)
			(layers "F.Cu" "F.Mask" "F.Paste")
			(net "P12V")
			(options
				(clearance outline)
				(anchor circle)
			)
			(primitives
				(gr_poly
					(pts
						(arc
							(start -0.1778 -0.2794)
							(mid -0.249642 -0.249642)
							(end -0.2794 -0.1778)
						)
						(arc
							(start -0.2794 0.1778)
							(mid -0.249642 0.249642)
							(end -0.1778 0.2794)
						)
						(arc
							(start 0.1778 0.2794)
							(mid 0.249642 0.249642)
							(end 0.2794 0.1778)
						)
						(arc
							(start 0.2794 -0.1778)
							(mid 0.249642 -0.249642)
							(end 0.1778 -0.2794)
						)
					)
					(width 0)
					(fill yes)
				)
			)
		)
		(pad "2" smd custom
			(at 0 0.4445 270)
			(size 0.1397 0.1397)
			(layers "F.Cu" "F.Mask" "F.Paste")
			(net "FAN_TACH1")
			(options
				(clearance outline)
				(anchor circle)
			)
			(primitives
				(gr_poly
					(pts
						(arc
							(start -0.1778 -0.2794)
							(mid -0.249642 -0.249642)
							(end -0.2794 -0.1778)
						)
						(arc
							(start -0.2794 0.1778)
							(mid -0.249642 0.249642)
							(end -0.1778 0.2794)
						)
						(arc
							(start 0.1778 0.2794)
							(mid 0.249642 0.249642)
							(end 0.2794 0.1778)
						)
						(arc
							(start 0.2794 -0.1778)
							(mid 0.249642 -0.249642)
							(end 0.1778 -0.2794)
						)
					)
					(width 0)
					(fill yes)
				)
			)
		)
	)
)
